# T6G (Grand Teton) — schematic netlist excerpt (pin names and nets, part order shuffled) for the footprints in the layout excerpt that follows; sources: Cadence DE-HDL packaged netlist, KiCad conversion of 04192023_DAF0TMB3IC0_F0TG_MB_C_brd_V02_OCP.brd

R6860  Q_RES  1K 1% CHIP  pkg 0402LF  page 362 : A = P1V8_AUX ; B = PWRGD_P0V9_RETIMER_CPU0_R

(kicad_pcb
	(version 20260206)
	(generator "pcbnew")
	(generator_version "10.0")
	(general
		(thickness 1.6)
		(legacy_teardrops no)
	)
	(paper "A4")
	(title_block
		(title "04192023_DAF0TMB3IC0_F0TG_MB_C_brd_V02_OCP.brd")
		(comment 1 "Grand Teton / footprints 105-105 of 8354")
	)
	(layers
		(0 "F.Cu" signal "TOP")
		(4 "In1.Cu" signal "GND")
		(6 "In2.Cu" signal "IN1")
		(8 "In3.Cu" signal "GND1")
		(10 "In4.Cu" signal "IN2")
		(12 "In5.Cu" signal "GND2")
		(14 "In6.Cu" signal "IN3")
		(16 "In7.Cu" signal "GND3")
		(18 "In8.Cu" signal "VCC")
		(20 "In9.Cu" signal "VCC1")
		(22 "In10.Cu" signal "GND4")
		(24 "In11.Cu" signal "IN4")
		(26 "In12.Cu" signal "GND5")
		(28 "In13.Cu" signal "IN5")
		(30 "In14.Cu" signal "GND6")
		(32 "In15.Cu" signal "IN6")
		(34 "In16.Cu" signal "GND7")
		(2 "B.Cu" signal "BOTTOM")
		(9 "F.Adhes" user "F.Adhesive")
		(11 "B.Adhes" user "B.Adhesive")
		(13 "F.Paste" user "Package Geometry/Pastemask Top")
		(15 "B.Paste" user "Package Geometry/Pastemask Bottom")
		(5 "F.SilkS" user "Ref Des/Silkscreen Top")
		(7 "B.SilkS" user "Ref Des/Silkscreen Bottom")
		(1 "F.Mask" user "Board Geometry/Soldermask Top")
		(3 "B.Mask" user "Board Geometry/Soldermask Bottom")
		(17 "Dwgs.User" user "User.Drawings")
		(19 "Cmts.User" user "User.Comments")
		(21 "Eco1.User" user "User.Eco1")
		(23 "Eco2.User" user "User.Eco2")
		(25 "Edge.Cuts" user "Board Geometry/Outline")
		(27 "Margin" user)
		(31 "F.CrtYd" user "Package Geometry/Place Bound Top")
		(29 "B.CrtYd" user "Package Geometry/Place Bound Bottom")
		(35 "F.Fab" user "Ref Des/Assembly Top")
		(33 "B.Fab" user "Ref Des/Assembly Bottom")
	)
	(footprint ""
		(layer "F.Cu")
		(at 438.257442 -428.918624 -90)
		(property "Reference" "R6860"
			(at 0 0 270)
			(layer "F.SilkS")
			(hide yes)
			(effects
				(font
					(size 1.27 1.27)
				)
			)
		)
		(property "Value" ""
			(at 0 0 270)
			(layer "F.Fab")
			(effects
				(font
					(size 1.27 1.27)
				)
			)
		)
		(duplicate_pad_numbers_are_jumpers no)
		(fp_line
			(start -0.7874 0.4064)
			(end -0.7874 -0.4064)
			(stroke
				(width 0.1524)
				(type default)
			)
			(layer "F.SilkS")
		)
		(fp_line
			(start 0.7874 0.4064)
			(end -0.7874 0.4064)
			(stroke
				(width 0.1524)
				(type default)
			)
			(layer "F.SilkS")
		)
		(fp_line
			(start -0.7874 -0.4064)
			(end 0.7874 -0.4064)
			(stroke
				(width 0.1524)
				(type default)
			)
			(layer "F.SilkS")
		)
		(fp_line
			(start 0.7874 -0.4064)
			(end 0.7874 0.4064)
			(stroke
				(width 0.1524)
				(type default)
			)
			(layer "F.SilkS")
		)
		(fp_line
			(start -0.67945 0.3048)
			(end -0.67945 -0.305054)
			(stroke
				(width 0.1)
				(type default)
			)
			(layer "F.Fab")
		)
		(fp_line
			(start -0.12065 0.3048)
			(end -0.67945 0.3048)
			(stroke
				(width 0.1)
				(type default)
			)
			(layer "F.Fab")
		)
		(fp_line
			(start 0.120396 0.3048)
			(end 0.120396 0.2794)
			(stroke
				(width 0.1)
				(type default)
			)
			(layer "F.Fab")
		)
		(fp_line
			(start 0.67945 0.3048)
			(end 0.120396 0.3048)
			(stroke
				(width 0.1)
				(type default)
			)
			(layer "F.Fab")
		)
		(fp_line
			(start -0.12065 0.2794)
			(end -0.12065 0.3048)
			(stroke
				(width 0.1)
				(type default)
			)
			(layer "F.Fab")
		)
		(fp_line
			(start 0.120396 0.2794)
			(end -0.12065 0.2794)
			(stroke
				(width 0.1)
				(type default)
			)
			(layer "F.Fab")
		)
		(fp_line
			(start -0.12065 -0.2794)
			(end 0.12065 -0.2794)
			(stroke
				(width 0.1)
				(type default)
			)
			(layer "F.Fab")
		)
		(fp_line
			(start 0.12065 -0.2794)
			(end 0.12065 -0.3048)
			(stroke
				(width 0.1)
				(type default)
			)
			(layer "F.Fab")
		)
		(fp_line
			(start 0.12065 -0.3048)
			(end 0.67945 -0.3048)
			(stroke
				(width 0.1)
				(type default)
			)
			(layer "F.Fab")
		)
		(fp_line
			(start 0.67945 -0.3048)
			(end 0.67945 0.3048)
			(stroke
				(width 0.1)
				(type default)
			)
			(layer "F.Fab")
		)
		(fp_line
			(start -0.67945 -0.305054)
			(end -0.12065 -0.305054)
			(stroke
				(width 0.1)
				(type default)
			)
			(layer "F.Fab")
		)
		(fp_line
			(start -0.12065 -0.305054)
			(end -0.12065 -0.2794)
			(stroke
				(width 0.1)
				(type default)
			)
			(layer "F.Fab")
		)
		(pad "1" smd circle
			(at -0.40005 0 270)
			(size 0 0)
			(layers "F.Cu" "F.Mask" "F.Paste")
			(net "P1V8_AUX")
		)
		(pad "2" smd circle
			(at 0.40005 0 270)
			(size 0 0)
			(layers "F.Cu" "F.Mask" "F.Paste")
			(net "PWRGD_P0V9_RETIMER_CPU0_R")
		)
	)
)
